(kicad_pcb
	(version 20260206)
	(generator "pcbnew")
	(generator_version "10.0")
	(general
		(thickness 1.6)
		(legacy_teardrops no)
	)
	(paper "A4")
	(title_block
		(title "v2-pdb — ms_pdb_v2.brd")
		(comment 1 "Open CloudServer (Microsoft) / footprints 270-276 of 348")
	)
	(layers
		(0 "F.Cu" signal "TOP")
		(4 "In1.Cu" signal "GND")
		(6 "In2.Cu" signal "IN1")
		(8 "In3.Cu" signal "VCC")
		(10 "In4.Cu" signal "VCC1")
		(12 "In5.Cu" signal "IN2")
		(14 "In6.Cu" signal "GND1")
		(2 "B.Cu" signal "BOTTOM")
		(9 "F.Adhes" user "F.Adhesive")
		(11 "B.Adhes" user "B.Adhesive")
		(13 "F.Paste" user "Package Geometry/Pastemask Top")
		(15 "B.Paste" user "Package Geometry/Pastemask Bottom")
		(5 "F.SilkS" user "Ref Des/Silkscreen Top")
		(7 "B.SilkS" user "Ref Des/Silkscreen Bottom")
		(1 "F.Mask" user "Board Geometry/Soldermask Top")
		(3 "B.Mask" user "Board Geometry/Soldermask Bottom")
		(17 "Dwgs.User" user "User.Drawings")
		(19 "Cmts.User" user "User.Comments")
		(21 "Eco1.User" user "User.Eco1")
		(23 "Eco2.User" user "User.Eco2")
		(25 "Edge.Cuts" user "Board Geometry/Outline")
		(27 "Margin" user)
		(31 "F.CrtYd" user "Package Geometry/Place Bound Top")
		(29 "B.CrtYd" user "Package Geometry/Place Bound Bottom")
		(35 "F.Fab" user "Ref Des/Assembly Top")
		(33 "B.Fab" user "Ref Des/Assembly Bottom")
	)
	(footprint ""
		(layer "F.Cu")
		(at 5.780024 -31.909766)
		(property "Reference" "J33"
			(at -1.9304 -3.978148 0)
			(unlocked yes)
			(layer "F.SilkS")
			(effects
				(font
					(size 0.7874 0.5842)
					(thickness 0.1524)
				)
				(justify left)
			)
		)
		(property "Value" ""
			(at 0 0 0)
			(layer "F.Fab")
			(effects
				(font
					(size 1.27 1.27)
				)
			)
		)
		(duplicate_pad_numbers_are_jumpers no)
		(fp_line
			(start -3.10007 0.199898)
			(end -3.10007 2.800096)
			(stroke
				(width 0.1524)
				(type default)
			)
			(layer "F.SilkS")
		)
		(fp_line
			(start -3.10007 2.800096)
			(end -1.89992 2.800096)
			(stroke
				(width 0.1524)
				(type default)
			)
			(layer "F.SilkS")
		)
		(fp_line
			(start -1.89992 -3.325114)
			(end -1.89992 0.199898)
			(stroke
				(width 0.1524)
				(type default)
			)
			(layer "F.SilkS")
		)
		(fp_line
			(start -1.89992 0.199898)
			(end -3.10007 0.199898)
			(stroke
				(width 0.1524)
				(type default)
			)
			(layer "F.SilkS")
		)
		(fp_line
			(start -1.89992 2.800096)
			(end -1.89992 6.325108)
			(stroke
				(width 0.1524)
				(type default)
			)
			(layer "F.SilkS")
		)
		(fp_line
			(start -1.89992 6.325108)
			(end 1.016 6.325108)
			(stroke
				(width 0.1524)
				(type default)
			)
			(layer "F.SilkS")
		)
		(fp_line
			(start 1.016 -3.325114)
			(end -1.89992 -3.325114)
			(stroke
				(width 0.1524)
				(type default)
			)
			(layer "F.SilkS")
		)
		(fp_line
			(start 2.469896 5.133594)
			(end 2.469896 -2.130806)
			(stroke
				(width 0.1524)
				(type default)
			)
			(layer "F.SilkS")
		)
		(fp_poly
			(pts
				(xy 0.8509 0.8509) (xy -0.8509 0.8509) (xy -0.8509 -0.8509) (xy 0.8509 -0.8509)
			)
			(stroke
				(width 0)
				(type default)
			)
			(fill no)
			(layer "B.CrtYd")
		)
		(fp_poly
			(pts
				(arc
					(start 0.8509 2.999994)
					(mid -0.8509 2.999994)
					(end 0.8509 2.999994)
				)
			)
			(stroke
				(width 0)
				(type default)
			)
			(fill no)
			(layer "B.CrtYd")
		)
		(fp_poly
			(pts
				(arc
					(start 2.874518 -2.999994)
					(mid 1.045718 -2.999994)
					(end 2.874518 -2.999994)
				)
			)
			(stroke
				(width 0)
				(type default)
			)
			(fill no)
			(layer "B.CrtYd")
		)
		(fp_poly
			(pts
				(arc
					(start 2.874518 5.999988)
					(mid 1.045718 5.999988)
					(end 2.874518 5.999988)
				)
			)
			(stroke
				(width 0)
				(type default)
			)
			(fill no)
			(layer "B.CrtYd")
		)
		(fp_poly
			(pts
				(xy 2.469896 5.233924) (xy 2.469896 -2.233676) (xy 2.8956 -2.233676) (xy 2.8956 -3.935476) (xy 1.0922 -3.935476)
				(xy 1.0922 -3.325114) (xy -1.89992 -3.325114) (xy -1.89992 0.199898) (xy -3.10007 0.199898) (xy -3.10007 2.800096)
				(xy -1.89992 2.800096) (xy -1.89992 6.325108) (xy 1.0922 6.325108) (xy 1.0922 6.935724) (xy 2.8956 6.935724)
				(xy 2.8956 5.233924)
			)
			(stroke
				(width 0)
				(type default)
			)
			(fill no)
			(layer "F.CrtYd")
		)
		(fp_line
			(start -3.10007 0.199898)
			(end -3.10007 2.800096)
			(stroke
				(width 0.1)
				(type default)
			)
			(layer "F.Fab")
		)
		(fp_line
			(start -3.10007 2.800096)
			(end -1.89992 2.800096)
			(stroke
				(width 0.1)
				(type default)
			)
			(layer "F.Fab")
		)
		(fp_line
			(start -1.89992 -3.325114)
			(end -1.89992 0.199898)
			(stroke
				(width 0.1)
				(type default)
			)
			(layer "F.Fab")
		)
		(fp_line
			(start -1.89992 0.199898)
			(end -3.10007 0.199898)
			(stroke
				(width 0.1)
				(type default)
			)
			(layer "F.Fab")
		)
		(fp_line
			(start -1.89992 2.800096)
			(end -1.89992 6.325108)
			(stroke
				(width 0.1)
				(type default)
			)
			(layer "F.Fab")
		)
		(fp_line
			(start -1.89992 6.325108)
			(end 2.469896 6.325108)
			(stroke
				(width 0.1)
				(type default)
			)
			(layer "F.Fab")
		)
		(fp_line
			(start 2.469896 -3.325114)
			(end -1.89992 -3.325114)
			(stroke
				(width 0.1)
				(type default)
			)
			(layer "F.Fab")
		)
		(fp_line
			(start 2.469896 6.325108)
			(end 2.469896 -3.325114)
			(stroke
				(width 0.1)
				(type default)
			)
			(layer "F.Fab")
		)
		(pad "" np_thru_hole circle
			(at 1.960118 -2.999994 90)
			(size 1.3208 1.3208)
			(drill 1.3208)
			(layers "*.Cu" "*.Mask")
			(clearance 0.381)
			(thermal_gap 0.381)
		)
		(pad "" np_thru_hole circle
			(at 1.960118 5.999988 90)
			(size 1.3208 1.3208)
			(drill 1.3208)
			(layers "*.Cu" "*.Mask")
			(clearance 0.381)
			(thermal_gap 0.381)
		)
		(pad "1" thru_hole rect
			(at 0 0 90)
			(size 1.6002 1.6002)
			(drill 1.0922)
			(layers "*.Cu" "*.Mask")
			(remove_unused_layers no)
			(net "CM_PWR_CTL_IN")
			(clearance 0)
			(padstack
				(mode front_inner_back)
				(layer "Inner"
					(shape circle)
					(size 1.6002 1.6002)
					(clearance 0)
				)
				(layer "B.Cu"
					(shape rect)
					(size 1.6002 1.6002)
					(clearance 0)
				)
			)
		)
		(pad "2" thru_hole circle
			(at 0 2.999994 90)
			(size 1.6002 1.6002)
			(drill 1.0922)
			(layers "*.Cu" "*.Mask")
			(remove_unused_layers no)
			(net "GND")
			(clearance 0)
		)
		(zone
			(layers "F.Cu" "B.Cu" "In1.Cu" "In2.Cu" "In3.Cu" "In4.Cu" "In5.Cu" "In6.Cu")
			(hatch none 0.5)
			(connect_pads
				(clearance 0)
			)
			(min_thickness 0.25)
			(keepout
				(tracks not_allowed)
				(vias allowed)
				(pads allowed)
				(copperpour not_allowed)
				(footprints allowed)
			)
			(placement
				(enabled no)
				(sheetname "")
			)
			(fill
				(thermal_gap 0.5)
				(thermal_bridge_width 0.5)
				(island_removal_mode 0)
			)
			(polygon
				(pts
					(arc
						(start 8.806942 -34.90976)
						(mid 6.673342 -34.90976)
						(end 8.806942 -34.90976)
					)
				)
			)
		)
		(zone
			(layers "F.Cu" "B.Cu" "In1.Cu" "In2.Cu" "In3.Cu" "In4.Cu" "In5.Cu" "In6.Cu")
			(hatch none 0.5)
			(connect_pads
				(clearance 0)
			)
			(min_thickness 0.25)
			(keepout
				(tracks not_allowed)
				(vias allowed)
				(pads allowed)
				(copperpour not_allowed)
				(footprints allowed)
			)
			(placement
				(enabled no)
				(sheetname "")
			)
			(fill
				(thermal_gap 0.5)
				(thermal_bridge_width 0.5)
				(island_removal_mode 0)
			)
			(polygon
				(pts
					(arc
						(start 8.806942 -25.909778)
						(mid 6.673342 -25.909778)
						(end 8.806942 -25.909778)
					)
				)
			)
		)
	)
	(footprint ""
		(layer "F.Cu")
		(at 91.399868 -508.96012)
		(property "Reference" "H24"
			(at -5.1308 -5.23113 0)
			(unlocked yes)
			(layer "F.SilkS")
			(effects
				(font
					(size 0.7874 0.5842)
					(thickness 0.1524)
				)
				(justify left)
			)
		)
		(property "Value" ""
			(at 0 0 0)
			(layer "F.Fab")
			(effects
				(font
					(size 1.27 1.27)
				)
			)
		)
		(duplicate_pad_numbers_are_jumpers no)
		(fp_circle
			(center 0 0)
			(end 4.826 0)
			(stroke
				(width 0.1524)
				(type default)
			)
			(fill no)
			(layer "F.SilkS")
		)
		(fp_circle
			(center 0 0)
			(end 4.826 0)
			(stroke
				(width 0.1524)
				(type default)
			)
			(fill no)
			(layer "B.SilkS")
		)
		(fp_poly
			(pts
				(arc
					(start 0 4.0132)
					(mid 0 -4.0132)
					(end 0 4.0132)
				)
			)
			(stroke
				(width 0)
				(type default)
			)
			(fill no)
			(layer "F.CrtYd")
		)
		(pad "" np_thru_hole circle
			(at 0 0)
			(size 8.001 8.001)
			(drill 8.001)
			(layers "*.Cu" "*.Mask")
			(clearance 0.381)
			(thermal_gap 0.381)
		)
		(zone
			(layers "F.Cu" "B.Cu" "In1.Cu" "In2.Cu" "In3.Cu" "In4.Cu" "In5.Cu" "In6.Cu")
			(hatch none 0.5)
			(connect_pads
				(clearance 0)
			)
			(min_thickness 0.25)
			(keepout
				(tracks not_allowed)
				(vias allowed)
				(pads allowed)
				(copperpour not_allowed)
				(footprints allowed)
			)
			(placement
				(enabled no)
				(sheetname "")
			)
			(fill
				(thermal_gap 0.5)
				(thermal_bridge_width 0.5)
				(island_removal_mode 0)
			)
			(polygon
				(pts
					(arc
						(start 91.399868 -504.43892)
						(mid 91.399868 -513.48132)
						(end 91.399868 -504.43892)
					)
				)
			)
		)
	)
	(footprint ""
		(layer "F.Cu")
		(at 26.947622 -108.230416)
		(property "Reference" "R7"
			(at -2.66192 0.007112 0)
			(unlocked yes)
			(layer "F.SilkS")
			(effects
				(font
					(size 0.7874 0.5842)
					(thickness 0.1524)
				)
				(justify left)
			)
		)
		(property "Value" ""
			(at 0 0 0)
			(layer "F.Fab")
			(effects
				(font
					(size 1.27 1.27)
				)
			)
		)
		(duplicate_pad_numbers_are_jumpers no)
		(fp_line
			(start -0.7874 -0.4064)
			(end 0.7874 -0.4064)
			(stroke
				(width 0.1524)
				(type default)
			)
			(layer "F.SilkS")
		)
		(fp_line
			(start -0.7874 0.4064)
			(end -0.7874 -0.4064)
			(stroke
				(width 0.1524)
				(type default)
			)
			(layer "F.SilkS")
		)
		(fp_line
			(start 0.7874 -0.4064)
			(end 0.7874 0.4064)
			(stroke
				(width 0.1524)
				(type default)
			)
			(layer "F.SilkS")
		)
		(fp_line
			(start 0.7874 0.4064)
			(end -0.7874 0.4064)
			(stroke
				(width 0.1524)
				(type default)
			)
			(layer "F.SilkS")
		)
		(fp_poly
			(pts
				(xy -0.508 0.2794) (xy -0.508 0.2286) (xy -0.635 0.2286) (xy -0.635 -0.254) (xy -0.5334 -0.254)
				(xy -0.5334 -0.2794) (xy 0.5334 -0.2794) (xy 0.5334 -0.254) (xy 0.635 -0.254) (xy 0.635 0.254) (xy 0.5334 0.254)
				(xy 0.5334 0.2794)
			)
			(stroke
				(width 0)
				(type default)
			)
			(fill no)
			(layer "F.CrtYd")
		)
		(pad "1" smd rect
			(at 0.40005 0)
			(size 0.4572 0.508)
			(layers "F.Cu" "F.Mask" "F.Paste")
			(net "PSU2_REMOTE_N")
		)
		(pad "2" smd rect
			(at -0.40005 0)
			(size 0.4572 0.508)
			(layers "F.Cu" "F.Mask" "F.Paste")
			(net "GND")
		)
	)
	(footprint ""
		(layer "F.Cu")
		(at 39.863776 -199.171814 180)
		(property "Reference" "R2"
			(at -1.93802 0.367792 0)
			(unlocked yes)
			(layer "F.SilkS")
			(effects
				(font
					(size 0.7874 0.5842)
					(thickness 0.1524)
				)
				(justify left)
			)
		)
		(property "Value" ""
			(at 0 0 180)
			(layer "F.Fab")
			(effects
				(font
					(size 1.27 1.27)
				)
			)
		)
		(duplicate_pad_numbers_are_jumpers no)
		(fp_line
			(start 0.7874 0.4064)
			(end -0.7874 0.4064)
			(stroke
				(width 0.1524)
				(type default)
			)
			(layer "F.SilkS")
		)
		(fp_line
			(start 0.7874 -0.4064)
			(end 0.7874 0.4064)
			(stroke
				(width 0.1524)
				(type default)
			)
			(layer "F.SilkS")
		)
		(fp_line
			(start -0.7874 0.4064)
			(end -0.7874 -0.4064)
			(stroke
				(width 0.1524)
				(type default)
			)
			(layer "F.SilkS")
		)
		(fp_line
			(start -0.7874 -0.4064)
			(end 0.7874 -0.4064)
			(stroke
				(width 0.1524)
				(type default)
			)
			(layer "F.SilkS")
		)
		(fp_poly
			(pts
				(xy -0.508 0.2794) (xy -0.508 0.2286) (xy -0.635 0.2286) (xy -0.635 -0.254) (xy -0.5334 -0.254)
				(xy -0.5334 -0.2794) (xy 0.5334 -0.2794) (xy 0.5334 -0.254) (xy 0.635 -0.254) (xy 0.635 0.254) (xy 0.5334 0.254)
				(xy 0.5334 0.2794)
			)
			(stroke
				(width 0)
				(type default)
			)
			(fill no)
			(layer "F.CrtYd")
		)
		(pad "1" smd rect
			(at 0.40005 0 180)
			(size 0.4572 0.508)
			(layers "F.Cu" "F.Mask" "F.Paste")
			(net "PSU3_REMOTE_P")
		)
		(pad "2" smd rect
			(at -0.40005 0 180)
			(size 0.4572 0.508)
			(layers "F.Cu" "F.Mask" "F.Paste")
			(net "P12V")
		)
	)
	(footprint ""
		(layer "F.Cu")
		(at 26.226008 -448.493388)
		(property "Reference" "R85"
			(at -2.9972 0.666242 0)
			(unlocked yes)
			(layer "F.SilkS")
			(effects
				(font
					(size 0.7874 0.5842)
					(thickness 0.1524)
				)
				(justify left)
			)
		)
		(property "Value" ""
			(at 0 0 0)
			(layer "F.Fab")
			(effects
				(font
					(size 1.27 1.27)
				)
			)
		)
		(duplicate_pad_numbers_are_jumpers no)
		(fp_line
			(start -0.7874 -0.4064)
			(end 0.7874 -0.4064)
			(stroke
				(width 0.1524)
				(type default)
			)
			(layer "F.SilkS")
		)
		(fp_line
			(start -0.7874 0.4064)
			(end -0.7874 -0.4064)
			(stroke
				(width 0.1524)
				(type default)
			)
			(layer "F.SilkS")
		)
		(fp_line
			(start 0.7874 -0.4064)
			(end 0.7874 0.4064)
			(stroke
				(width 0.1524)
				(type default)
			)
			(layer "F.SilkS")
		)
		(fp_line
			(start 0.7874 0.4064)
			(end -0.7874 0.4064)
			(stroke
				(width 0.1524)
				(type default)
			)
			(layer "F.SilkS")
		)
		(fp_poly
			(pts
				(xy -0.508 0.2794) (xy -0.508 0.2286) (xy -0.635 0.2286) (xy -0.635 -0.254) (xy -0.5334 -0.254)
				(xy -0.5334 -0.2794) (xy 0.5334 -0.2794) (xy 0.5334 -0.254) (xy 0.635 -0.254) (xy 0.635 0.254) (xy 0.5334 0.254)
				(xy 0.5334 0.2794)
			)
			(stroke
				(width 0)
				(type default)
			)
			(fill no)
			(layer "F.CrtYd")
		)
		(pad "1" smd rect
			(at 0.40005 0)
			(size 0.4572 0.508)
			(layers "F.Cu" "F.Mask" "F.Paste")
			(net "PSU6_RESET")
		)
		(pad "2" smd rect
			(at -0.40005 0)
			(size 0.4572 0.508)
			(layers "F.Cu" "F.Mask" "F.Paste")
			(net "GND")
		)
	)
	(footprint ""
		(layer "F.Cu")
		(at 39.936674 -464.36915 180)
		(property "Reference" "R17"
			(at -1.699514 0.166624 0)
			(unlocked yes)
			(layer "F.SilkS")
			(effects
				(font
					(size 0.7874 0.5842)
					(thickness 0.1524)
				)
				(justify left)
			)
		)
		(property "Value" ""
			(at 0 0 180)
			(layer "F.Fab")
			(effects
				(font
					(size 1.27 1.27)
				)
			)
		)
		(duplicate_pad_numbers_are_jumpers no)
		(fp_line
			(start 0.7874 0.4064)
			(end -0.7874 0.4064)
			(stroke
				(width 0.1524)
				(type default)
			)
			(layer "F.SilkS")
		)
		(fp_line
			(start 0.7874 -0.4064)
			(end 0.7874 0.4064)
			(stroke
				(width 0.1524)
				(type default)
			)
			(layer "F.SilkS")
		)
		(fp_line
			(start -0.7874 0.4064)
			(end -0.7874 -0.4064)
			(stroke
				(width 0.1524)
				(type default)
			)
			(layer "F.SilkS")
		)
		(fp_line
			(start -0.7874 -0.4064)
			(end 0.7874 -0.4064)
			(stroke
				(width 0.1524)
				(type default)
			)
			(layer "F.SilkS")
		)
		(fp_poly
			(pts
				(xy -0.508 0.2794) (xy -0.508 0.2286) (xy -0.635 0.2286) (xy -0.635 -0.254) (xy -0.5334 -0.254)
				(xy -0.5334 -0.2794) (xy 0.5334 -0.2794) (xy 0.5334 -0.254) (xy 0.635 -0.254) (xy 0.635 0.254) (xy 0.5334 0.254)
				(xy 0.5334 0.2794)
			)
			(stroke
				(width 0)
				(type default)
			)
			(fill no)
			(layer "F.CrtYd")
		)
		(pad "1" smd rect
			(at 0.40005 0 180)
			(size 0.4572 0.508)
			(layers "F.Cu" "F.Mask" "F.Paste")
			(net "PSU6_REMOTE_P")
		)
		(pad "2" smd rect
			(at -0.40005 0 180)
			(size 0.4572 0.508)
			(layers "F.Cu" "F.Mask" "F.Paste")
			(net "P12V")
		)
	)
	(footprint ""
		(layer "F.Cu")
		(at 40.86098 -283.09824 -90)
		(property "Reference" "R21"
			(at 0.946912 -2.85623 90)
			(unlocked yes)
			(layer "F.SilkS")
			(effects
				(font
					(size 0.7874 0.5842)
					(thickness 0.1524)
				)
				(justify left)
			)
		)
		(property "Value" ""
			(at 0 0 270)
			(layer "F.Fab")
			(effects
				(font
					(size 1.27 1.27)
				)
			)
		)
		(duplicate_pad_numbers_are_jumpers no)
		(fp_line
			(start -0.7874 0.4064)
			(end -0.7874 -0.4064)
			(stroke
				(width 0.1524)
				(type default)
			)
			(layer "F.SilkS")
		)
		(fp_line
			(start 0.7874 0.4064)
			(end -0.7874 0.4064)
			(stroke
				(width 0.1524)
				(type default)
			)
			(layer "F.SilkS")
		)
		(fp_line
			(start -0.7874 -0.4064)
			(end 0.7874 -0.4064)
			(stroke
				(width 0.1524)
				(type default)
			)
			(layer "F.SilkS")
		)
		(fp_line
			(start 0.7874 -0.4064)
			(end 0.7874 0.4064)
			(stroke
				(width 0.1524)
				(type default)
			)
			(layer "F.SilkS")
		)
		(fp_poly
			(pts
				(xy -0.508 0.2794) (xy -0.508 0.2286) (xy -0.635 0.2286) (xy -0.635 -0.254) (xy -0.5334 -0.254)
				(xy -0.5334 -0.2794) (xy 0.5334 -0.2794) (xy 0.5334 -0.254) (xy 0.635 -0.254) (xy 0.635 0.254) (xy 0.5334 0.254)
				(xy 0.5334 0.2794)
			)
			(stroke
				(width 0)
				(type default)
			)
			(fill no)
			(layer "F.CrtYd")
		)
		(pad "1" smd rect
			(at 0.40005 0 270)
			(size 0.4572 0.508)
			(layers "F.Cu" "F.Mask" "F.Paste")
			(net "PSU4_AD0")
		)
		(pad "2" smd rect
			(at -0.40005 0 270)
			(size 0.4572 0.508)
			(layers "F.Cu" "F.Mask" "F.Paste")
			(net "GND")
		)
	)
)
